(kicad_pcb
	(version 20241229)
	(generator "pcbnew")
	(generator_version "9.0")
	(general
		(thickness 1.62)
		(legacy_teardrops no)
	)
	(paper "A3")
	(title_block
		(title "COM Express 7 Baseboard")
		(date "2025-02-04")
		(rev "1.1.2")
		(company "Antmicro Ltd")
		(comment 1 "www.antmicro.com")
		(comment 9 "footprints 716-719 of 802")
	)
	(layers
		(0 "F.Cu" signal)
		(4 "In1.Cu" signal)
		(6 "In2.Cu" signal)
		(8 "In3.Cu" signal)
		(10 "In4.Cu" signal)
		(12 "In5.Cu" signal)
		(14 "In6.Cu" signal)
		(2 "B.Cu" signal)
		(9 "F.Adhes" user "F.Adhesive")
		(11 "B.Adhes" user "B.Adhesive")
		(13 "F.Paste" user)
		(15 "B.Paste" user)
		(5 "F.SilkS" user "F.Silkscreen")
		(7 "B.SilkS" user "B.Silkscreen")
		(1 "F.Mask" user)
		(3 "B.Mask" user)
		(17 "Dwgs.User" user "User.Drawings")
		(19 "Cmts.User" user "User.Comments")
		(21 "Eco1.User" user "User.Eco1")
		(23 "Eco2.User" user "User.Eco2")
		(25 "Edge.Cuts" user)
		(27 "Margin" user)
		(31 "F.CrtYd" user "F.Courtyard")
		(29 "B.CrtYd" user "B.Courtyard")
		(35 "F.Fab" user)
		(33 "B.Fab" user)
	)
	(footprint "antmicro-footprints:SOT-23-3"
		(layer "B.Cu")
		(at 140.7 135.81)
		(property "Reference" "D23"
			(at -3.8 1.95 0)
			(layer "B.SilkS")
			(effects
				(font
					(size 0.7 0.7)
					(thickness 0.15)
				)
				(justify right bottom mirror)
			)
		)
		(property "Value" "BAT54C"
			(at -1.9 -2.7 0)
			(layer "B.Fab")
			(effects
				(font
					(size 0.7 0.7)
					(thickness 0.15)
				)
				(justify right bottom mirror)
			)
		)
		(property "Datasheet" "https://diotec.com/request/datasheet/bat54.pdf"
			(at 0 0 0)
			(layer "F.Fab")
			(hide yes)
			(effects
				(font
					(size 1.27 1.27)
					(thickness 0.15)
				)
			)
		)
		(property "Author" "Antmicro"
			(at 0 0 0)
			(layer "B.Fab")
			(hide yes)
			(effects
				(font
					(size 1 1)
					(thickness 0.15)
				)
				(justify mirror)
			)
		)
		(property "License" "Apache-2.0"
			(at 0 0 0)
			(layer "B.Fab")
			(hide yes)
			(effects
				(font
					(size 1 1)
					(thickness 0.15)
				)
				(justify mirror)
			)
		)
		(property "MPN" "BAT54C"
			(at 0 0 0)
			(layer "B.Fab")
			(hide yes)
			(effects
				(font
					(size 1 1)
					(thickness 0.15)
				)
				(justify mirror)
			)
		)
		(property "Manufacturer" "Diotec Semiconductor"
			(at 0 0 0)
			(layer "B.Fab")
			(hide yes)
			(effects
				(font
					(size 1 1)
					(thickness 0.15)
				)
				(justify mirror)
			)
		)
		(sheetname "KR to SFI #2")
		(sheetfile "kr_sfi.kicad_sch")
		(attr smd)
		(fp_line
			(start -0.85 1.35)
			(end -1.45 1.35)
			(stroke
				(width 0.15)
				(type solid)
			)
			(layer "B.SilkS")
		)
		(fp_line
			(start -0.7 -1.5)
			(end 0.7 -1.5)
			(stroke
				(width 0.15)
				(type solid)
			)
			(layer "B.SilkS")
		)
		(fp_line
			(start -0.7 -1.35)
			(end -0.7 -1.5)
			(stroke
				(width 0.15)
				(type solid)
			)
			(layer "B.SilkS")
		)
		(fp_line
			(start -0.7 1.5)
			(end -0.85 1.35)
			(stroke
				(width 0.15)
				(type solid)
			)
			(layer "B.SilkS")
		)
		(fp_line
			(start -0.7 1.5)
			(end 0.7 1.5)
			(stroke
				(width 0.15)
				(type solid)
			)
			(layer "B.SilkS")
		)
		(fp_line
			(start 0.7 -1.5)
			(end 0.7 -0.4)
			(stroke
				(width 0.15)
				(type solid)
			)
			(layer "B.SilkS")
		)
		(fp_line
			(start 0.7 1.5)
			(end 0.7 0.4)
			(stroke
				(width 0.15)
				(type solid)
			)
			(layer "B.SilkS")
		)
		(fp_line
			(start -1.75 -1.4)
			(end -0.85 -1.4)
			(stroke
				(width 0.05)
				(type solid)
			)
			(layer "B.CrtYd")
		)
		(fp_line
			(start -1.75 -0.5)
			(end -1.75 -1.4)
			(stroke
				(width 0.05)
				(type solid)
			)
			(layer "B.CrtYd")
		)
		(fp_line
			(start -1.75 0.5)
			(end -0.85 0.5)
			(stroke
				(width 0.05)
				(type solid)
			)
			(layer "B.CrtYd")
		)
		(fp_line
			(start -1.75 1.4)
			(end -1.75 0.5)
			(stroke
				(width 0.05)
				(type solid)
			)
			(layer "B.CrtYd")
		)
		(fp_line
			(start -1.75 1.4)
			(end -0.9 1.4)
			(stroke
				(width 0.05)
				(type solid)
			)
			(layer "B.CrtYd")
		)
		(fp_line
			(start -0.9 1.4)
			(end -0.9 1.6)
			(stroke
				(width 0.05)
				(type solid)
			)
			(layer "B.CrtYd")
		)
		(fp_line
			(start -0.85 -1.65)
			(end 0.85 -1.65)
			(stroke
				(width 0.05)
				(type solid)
			)
			(layer "B.CrtYd")
		)
		(fp_line
			(start -0.85 -1.4)
			(end -0.85 -1.65)
			(stroke
				(width 0.05)
				(type solid)
			)
			(layer "B.CrtYd")
		)
		(fp_line
			(start -0.85 -0.5)
			(end -1.75 -0.5)
			(stroke
				(width 0.05)
				(type solid)
			)
			(layer "B.CrtYd")
		)
		(fp_line
			(start -0.85 0.5)
			(end -0.85 -0.5)
			(stroke
				(width 0.05)
				(type solid)
			)
			(layer "B.CrtYd")
		)
		(fp_line
			(start 0.825 0.45)
			(end 0.825 1.6)
			(stroke
				(width 0.05)
				(type solid)
			)
			(layer "B.CrtYd")
		)
		(fp_line
			(start 0.825 1.6)
			(end -0.9 1.6)
			(stroke
				(width 0.05)
				(type solid)
			)
			(layer "B.CrtYd")
		)
		(fp_line
			(start 0.85 -1.65)
			(end 0.85 -0.45)
			(stroke
				(width 0.05)
				(type solid)
			)
			(layer "B.CrtYd")
		)
		(fp_line
			(start 0.85 -0.45)
			(end 1.75 -0.45)
			(stroke
				(width 0.05)
				(type solid)
			)
			(layer "B.CrtYd")
		)
		(fp_line
			(start 1.75 -0.45)
			(end 1.75 0.45)
			(stroke
				(width 0.05)
				(type solid)
			)
			(layer "B.CrtYd")
		)
		(fp_line
			(start 1.75 0.45)
			(end 0.825 0.45)
			(stroke
				(width 0.05)
				(type solid)
			)
			(layer "B.CrtYd")
		)
		(fp_line
			(start -0.712 -1.523)
			(end -0.712 1.325)
			(stroke
				(width 0.15)
				(type solid)
			)
			(layer "B.Fab")
		)
		(fp_line
			(start -0.712 1.325)
			(end -0.437 1.526)
			(stroke
				(width 0.15)
				(type solid)
			)
			(layer "B.Fab")
		)
		(fp_line
			(start 0.688 -1.519)
			(end -0.712 -1.519)
			(stroke
				(width 0.15)
				(type solid)
			)
			(layer "B.Fab")
		)
		(fp_line
			(start 0.688 1.52)
			(end 0.688 -1.519)
			(stroke
				(width 0.15)
				(type solid)
			)
			(layer "B.Fab")
		)
		(fp_line
			(start 0.688 1.526)
			(end -0.437 1.526)
			(stroke
				(width 0.15)
				(type solid)
			)
			(layer "B.Fab")
		)
		(pad "1" smd roundrect
			(at -1.1 0.951)
			(size 1 0.6)
			(layers "B.Cu" "B.Mask" "B.Paste")
			(roundrect_rratio 0.15)
			(net 143 "/2xSFP+/KR to SFI #2/~{RESET}")
			(pinfunction "1")
			(pintype "passive")
			(teardrops
				(best_length_ratio 0.2)
				(max_length 1)
				(best_width_ratio 0.9)
				(max_width 2)
				(curved_edges yes)
				(filter_ratio 0.9)
				(enabled yes)
				(allow_two_segments yes)
				(prefer_zone_connections yes)
			)
		)
		(pad "2" smd roundrect
			(at -1.1 -0.949)
			(size 1 0.6)
			(layers "B.Cu" "B.Mask" "B.Paste")
			(roundrect_rratio 0.15)
			(net 143 "/2xSFP+/KR to SFI #2/~{RESET}")
			(pinfunction "2")
			(pintype "passive")
			(teardrops
				(best_length_ratio 0.2)
				(max_length 1)
				(best_width_ratio 0.9)
				(max_width 2)
				(curved_edges yes)
				(filter_ratio 0.9)
				(enabled yes)
				(allow_two_segments yes)
				(prefer_zone_connections yes)
			)
		)
		(pad "3" smd roundrect
			(at 1.1 0.0005)
			(size 1 0.6)
			(layers "B.Cu" "B.Mask" "B.Paste")
			(roundrect_rratio 0.15)
			(net 142 "/2xSFP+/PHY0_{RESET}")
			(pinfunction "3")
			(pintype "passive")
			(teardrops
				(best_length_ratio 0.2)
				(max_length 1)
				(best_width_ratio 0.9)
				(max_width 2)
				(curved_edges yes)
				(filter_ratio 0.9)
				(enabled yes)
				(allow_two_segments yes)
				(prefer_zone_connections yes)
			)
		)
	)
	(footprint "antmicro-footprints:R_0402_1005Metric"
		(layer "B.Cu")
		(at 123.4 99.86)
		(descr "Resistor SMD 0402")
		(tags "resistor SMD 0402")
		(property "Reference" "R9"
			(at 0.9 0.45 0)
			(layer "B.SilkS")
			(effects
				(font
					(size 0.7 0.7)
					(thickness 0.15)
				)
				(justify right bottom mirror)
			)
		)
		(property "Value" "R_470R_0402"
			(at -1.011843 -1.772047 0)
			(layer "B.Fab")
			(effects
				(font
					(size 0.7 0.7)
					(thickness 0.15)
				)
				(justify right bottom mirror)
			)
		)
		(property "Datasheet" "https://www.bourns.com/docs/product-datasheets/cr.pdf"
			(at 0 0 0)
			(layer "F.Fab")
			(hide yes)
			(effects
				(font
					(size 1.27 1.27)
					(thickness 0.15)
				)
			)
		)
		(property "Author" "Antmicro"
			(at 0 0 0)
			(layer "B.Fab")
			(hide yes)
			(effects
				(font
					(size 1 1)
					(thickness 0.15)
				)
				(justify mirror)
			)
		)
		(property "License" "Apache-2.0"
			(at 0 0 0)
			(layer "B.Fab")
			(hide yes)
			(effects
				(font
					(size 1 1)
					(thickness 0.15)
				)
				(justify mirror)
			)
		)
		(property "MPN" "CR0402-FX-4700GLF"
			(at 0 0 0)
			(layer "B.Fab")
			(hide yes)
			(effects
				(font
					(size 1 1)
					(thickness 0.15)
				)
				(justify mirror)
			)
		)
		(property "Manufacturer" "Bourns"
			(at 0 0 0)
			(layer "B.Fab")
			(hide yes)
			(effects
				(font
					(size 1 1)
					(thickness 0.15)
				)
				(justify mirror)
			)
		)
		(property "Public" "False"
			(at 0 0 0)
			(layer "B.Fab")
			(hide yes)
			(effects
				(font
					(size 1 1)
					(thickness 0.15)
				)
				(justify mirror)
			)
		)
		(property "Tolerance" "1%"
			(at 0 0 0)
			(layer "B.Fab")
			(hide yes)
			(effects
				(font
					(size 1 1)
					(thickness 0.15)
				)
				(justify mirror)
			)
		)
		(property "Val" "470R"
			(at 0 0 0)
			(layer "B.Fab")
			(hide yes)
			(effects
				(font
					(size 1 1)
					(thickness 0.15)
				)
				(justify mirror)
			)
		)
		(sheetname "2xUSB3.0+RJ45")
		(sheetfile "usb3+rj45.kicad_sch")
		(attr smd dnp)
		(fp_rect
			(start -0.925 0.47)
			(end 0.925 -0.47)
			(stroke
				(width 0.05)
				(type default)
			)
			(fill no)
			(layer "B.CrtYd")
		)
		(fp_rect
			(start -0.5 0.25)
			(end 0.5 -0.25)
			(stroke
				(width 0.15)
				(type solid)
			)
			(fill no)
			(layer "B.Fab")
		)
		(pad "1" smd roundrect
			(at -0.48 0)
			(size 0.59 0.64)
			(layers "B.Cu" "B.Mask" "B.Paste")
			(roundrect_rratio 0.25)
			(net 155 "Net-(J1A-LED_D2)")
			(pintype "passive")
			(teardrops
				(best_length_ratio 0.2)
				(max_length 1)
				(best_width_ratio 0.9)
				(max_width 2)
				(curved_edges yes)
				(filter_ratio 0.9)
				(enabled yes)
				(allow_two_segments yes)
				(prefer_zone_connections yes)
			)
		)
		(pad "2" smd roundrect
			(at 0.48 0)
			(size 0.59 0.64)
			(layers "B.Cu" "B.Mask" "B.Paste")
			(roundrect_rratio 0.25)
			(net 2 "+3V3")
			(pintype "passive")
			(teardrops
				(best_length_ratio 0.2)
				(max_length 1)
				(best_width_ratio 0.9)
				(max_width 2)
				(curved_edges yes)
				(filter_ratio 0.9)
				(enabled yes)
				(allow_two_segments yes)
				(prefer_zone_connections yes)
			)
		)
	)
	(footprint "antmicro-footprints:R_0402_1005Metric"
		(layer "B.Cu")
		(at 107.5 162.06 180)
		(descr "Resistor SMD 0402")
		(tags "resistor SMD 0402")
		(property "Reference" "R84"
			(at -3 -0.43 0)
			(layer "B.SilkS")
			(effects
				(font
					(size 0.7 0.7)
					(thickness 0.15)
				)
				(justify left bottom mirror)
			)
		)
		(property "Value" "R_0R_0402"
			(at -1.011843 -1.772047 0)
			(layer "B.Fab")
			(effects
				(font
					(size 0.7 0.7)
					(thickness 0.15)
				)
				(justify left bottom mirror)
			)
		)
		(property "Datasheet" "https://industrial.panasonic.com/cdbs/www-data/pdf/RDA0000/AOA0000C301.pdf"
			(at 0 0 180)
			(layer "F.Fab")
			(hide yes)
			(effects
				(font
					(size 1.27 1.27)
					(thickness 0.15)
				)
			)
		)
		(property "Author" "Antmicro"
			(at 215 324.12 0)
			(layer "B.Fab")
			(hide yes)
			(effects
				(font
					(size 1 1)
					(thickness 0.15)
				)
				(justify mirror)
			)
		)
		(property "Current" "1A"
			(at 215 324.12 0)
			(layer "B.Fab")
			(hide yes)
			(effects
				(font
					(size 1 1)
					(thickness 0.15)
				)
				(justify mirror)
			)
		)
		(property "License" "Apache-2.0"
			(at 215 324.12 0)
			(layer "B.Fab")
			(hide yes)
			(effects
				(font
					(size 1 1)
					(thickness 0.15)
				)
				(justify mirror)
			)
		)
		(property "MPN" "ERJ2GE0R00X"
			(at 215 324.12 0)
			(layer "B.Fab")
			(hide yes)
			(effects
				(font
					(size 1 1)
					(thickness 0.15)
				)
				(justify mirror)
			)
		)
		(property "Manufacturer" "Panasonic"
			(at 215 324.12 0)
			(layer "B.Fab")
			(hide yes)
			(effects
				(font
					(size 1 1)
					(thickness 0.15)
				)
				(justify mirror)
			)
		)
		(property "Public" "False"
			(at 215 324.12 0)
			(layer "B.Fab")
			(hide yes)
			(effects
				(font
					(size 1 1)
					(thickness 0.15)
				)
				(justify mirror)
			)
		)
		(property "Tolerance" ""
			(at 215 324.12 0)
			(layer "B.Fab")
			(hide yes)
			(effects
				(font
					(size 1 1)
					(thickness 0.15)
				)
				(justify mirror)
			)
		)
		(property "Val" "0R"
			(at 215 324.12 0)
			(layer "B.Fab")
			(hide yes)
			(effects
				(font
					(size 1 1)
					(thickness 0.15)
				)
				(justify mirror)
			)
		)
		(sheetname "OCuLink")
		(sheetfile "oculink.kicad_sch")
		(attr smd)
		(fp_rect
			(start -0.925 0.47)
			(end 0.925 -0.47)
			(stroke
				(width 0.05)
				(type default)
			)
			(fill no)
			(layer "B.CrtYd")
		)
		(fp_rect
			(start -0.5 0.25)
			(end 0.5 -0.25)
			(stroke
				(width 0.15)
				(type solid)
			)
			(fill no)
			(layer "B.Fab")
		)
		(pad "1" smd roundrect
			(at -0.48 0 180)
			(size 0.59 0.64)
			(layers "B.Cu" "B.Mask" "B.Paste")
			(roundrect_rratio 0.25)
			(net 358 "/Com Express 7 MGMT/SMBus.SDA")
			(pintype "passive")
			(teardrops
				(best_length_ratio 0.2)
				(max_length 1)
				(best_width_ratio 0.9)
				(max_width 2)
				(curved_edges yes)
				(filter_ratio 0.9)
				(enabled yes)
				(allow_two_segments yes)
				(prefer_zone_connections yes)
			)
		)
		(pad "2" smd roundrect
			(at 0.48 0 180)
			(size 0.59 0.64)
			(layers "B.Cu" "B.Mask" "B.Paste")
			(roundrect_rratio 0.25)
			(net 199 "/OCuLink/SDA")
			(pintype "passive")
			(teardrops
				(best_length_ratio 0.2)
				(max_length 1)
				(best_width_ratio 0.9)
				(max_width 2)
				(curved_edges yes)
				(filter_ratio 0.9)
				(enabled yes)
				(allow_two_segments yes)
				(prefer_zone_connections yes)
			)
		)
	)
	(footprint "antmicro-footprints:C_1210_3225Metric"
		(layer "B.Cu")
		(at 140.6 105.2 180)
		(descr "Capacitor SMD 1210")
		(tags "capacitor SMD 1210")
		(property "Reference" "C12"
			(at -1.105 2.7 0)
			(layer "B.SilkS")
			(effects
				(font
					(size 0.7 0.7)
					(thickness 0.15)
				)
				(justify left top mirror)
			)
		)
		(property "Value" "C_1n_1210_2kV"
			(at 0 -2.749001 0)
			(layer "B.Fab")
			(effects
				(font
					(size 0.7 0.7)
					(thickness 0.15)
				)
				(justify left top mirror)
			)
		)
		(property "Datasheet" "https://www.kemet.com/en/us/capacitors/product/C1210C102KGRACTU.html"
			(at 0 0 0)
			(layer "B.Fab")
			(hide yes)
			(effects
				(font
					(size 1.27 1.27)
					(thickness 0.15)
				)
				(justify mirror)
			)
		)
		(property "Author" "Antmicro"
			(at 279.39 -214.52 0)
			(layer "B.Fab")
			(hide yes)
			(effects
				(font
					(size 1 1)
					(thickness 0.15)
				)
				(justify mirror)
			)
		)
		(property "Dielectric" ""
			(at 279.39 -214.52 0)
			(layer "B.Fab")
			(hide yes)
			(effects
				(font
					(size 1 1)
					(thickness 0.15)
				)
				(justify mirror)
			)
		)
		(property "License" "Apache-2.0"
			(at 279.39 -214.52 0)
			(layer "B.Fab")
			(hide yes)
			(effects
				(font
					(size 1 1)
					(thickness 0.15)
				)
				(justify mirror)
			)
		)
		(property "MPN" "C1210C102KGRACTU"
			(at 279.39 -214.52 0)
			(layer "B.Fab")
			(hide yes)
			(effects
				(font
					(size 1 1)
					(thickness 0.15)
				)
				(justify mirror)
			)
		)
		(property "Manufacturer" "KEMET"
			(at 279.39 -214.52 0)
			(layer "B.Fab")
			(hide yes)
			(effects
				(font
					(size 1 1)
					(thickness 0.15)
				)
				(justify mirror)
			)
		)
		(property "Public" "False"
			(at 279.39 -214.52 0)
			(layer "B.Fab")
			(hide yes)
			(effects
				(font
					(size 1 1)
					(thickness 0.15)
				)
				(justify mirror)
			)
		)
		(property "Val" "1n"
			(at 279.39 -214.52 0)
			(layer "B.Fab")
			(hide yes)
			(effects
				(font
					(size 1 1)
					(thickness 0.15)
				)
				(justify mirror)
			)
		)
		(property "Voltage" "2kV"
			(at 279.39 -214.52 0)
			(layer "B.Fab")
			(hide yes)
			(effects
				(font
					(size 1 1)
					(thickness 0.15)
				)
				(justify mirror)
			)
		)
		(sheetname "2xUSB3.0+RJ45")
		(sheetfile "usb3+rj45.kicad_sch")
		(attr smd)
		(fp_line
			(start 0.3 1.39)
			(end -0.3 1.39)
			(stroke
				(width 0.15)
				(type solid)
			)
			(layer "B.SilkS")
		)
		(fp_line
			(start 0.3 -1.39)
			(end -0.3 -1.39)
			(stroke
				(width 0.15)
				(type solid)
			)
			(layer "B.SilkS")
		)
		(fp_rect
			(start -2.1 1.75)
			(end 2.1 -1.75)
			(stroke
				(width 0.05)
				(type solid)
			)
			(fill no)
			(layer "B.CrtYd")
		)
		(fp_rect
			(start -1.6 1.25)
			(end 1.6 -1.25)
			(stroke
				(width 0.15)
				(type solid)
			)
			(fill no)
			(layer "B.Fab")
		)
		(pad "1" smd rect
			(at -1.145 0 180)
			(size 1.52 3.05)
			(layers "B.Cu" "B.Mask" "B.Paste")
			(net 1 "GND")
			(pintype "passive")
			(teardrops
				(best_length_ratio 0.2)
				(max_length 1)
				(best_width_ratio 0.9)
				(max_width 2)
				(curved_edges yes)
				(filter_ratio 0.9)
				(enabled yes)
				(allow_two_segments yes)
				(prefer_zone_connections yes)
			)
		)
		(pad "2" smd rect
			(at 1.145 0 180)
			(size 1.52 3.05)
			(layers "B.Cu" "B.Mask" "B.Paste")
			(net 50 "Net-(C12-Pad2)")
			(pintype "passive")
			(teardrops
				(best_length_ratio 0.2)
				(max_length 1)
				(best_width_ratio 0.9)
				(max_width 2)
				(curved_edges yes)
				(filter_ratio 0.9)
				(enabled yes)
				(allow_two_segments yes)
				(prefer_zone_connections yes)
			)
		)
	)
)
